(kicad_pcb
	(version 20260206)
	(generator "pcbnew")
	(generator_version "10.0")
	(general
		(thickness 1.6)
		(legacy_teardrops no)
	)
	(paper "A4")
	(title_block
		(title "timecard-production-celestica-r4006 — R4006-B0001-02_R01.brd")
		(comment 1 "Time Appliance Project (Time Card) / footprints 618-623 of 1113")
	)
	(layers
		(0 "F.Cu" signal "TOP")
		(4 "In1.Cu" signal "L02_GND1")
		(6 "In2.Cu" signal "L03_SIG1")
		(8 "In3.Cu" signal "L04_GND2")
		(10 "In4.Cu" signal "L05_VCC1")
		(12 "In5.Cu" signal "L06_VCC2")
		(14 "In6.Cu" signal "L07_GND3")
		(16 "In7.Cu" signal "L08_SIG2")
		(18 "In8.Cu" signal "L09_GND4")
		(2 "B.Cu" signal "BOTTOM")
		(9 "F.Adhes" user "F.Adhesive")
		(11 "B.Adhes" user "B.Adhesive")
		(13 "F.Paste" user "Package Geometry/Pastemask Top")
		(15 "B.Paste" user "Package Geometry/Pastemask Bottom")
		(5 "F.SilkS" user "Ref Des/Silkscreen Top")
		(7 "B.SilkS" user "Ref Des/Silkscreen Bottom")
		(1 "F.Mask" user "Board Geometry/Soldermask Top")
		(3 "B.Mask" user "Board Geometry/Soldermask Bottom")
		(17 "Dwgs.User" user "User.Drawings")
		(19 "Cmts.User" user "User.Comments")
		(21 "Eco1.User" user "User.Eco1")
		(23 "Eco2.User" user "User.Eco2")
		(25 "Edge.Cuts" user "Board Geometry/Outline")
		(27 "Margin" user)
		(31 "F.CrtYd" user "Package Geometry/Place Bound Top")
		(29 "B.CrtYd" user "Package Geometry/Place Bound Bottom")
		(35 "F.Fab" user "Ref Des/Assembly Top")
		(33 "B.Fab" user "Ref Des/Assembly Bottom")
	)
	(footprint ""
		(layer "F.Cu")
		(at 33.77438 -17.9832 180)
		(property "Reference" "R184"
			(at -2.80162 -1.38557 0)
			(unlocked yes)
			(layer "F.SilkS")
			(effects
				(font
					(size 0.7874 0.5842)
					(thickness 0.1524)
				)
			)
		)
		(property "Value" "VAL*"
			(at 0.02032 2.13233 180)
			(unlocked yes)
			(layer "F.Fab")
			(hide yes)
			(effects
				(font
					(size 0.7874 0.5842)
					(thickness 0.1524)
				)
			)
		)
		(property "Tolerance" "TOL*"
			(at 0.044704 3.05435 180)
			(unlocked yes)
			(layer "Cmts.User")
			(hide yes)
			(effects
				(font
					(size 0.7874 0.5842)
					(thickness 0.1524)
				)
			)
		)
		(property "User Part Number" "PARTNUM*"
			(at 0.02032 4.024884 180)
			(unlocked yes)
			(layer "Cmts.User")
			(hide yes)
			(effects
				(font
					(size 0.7874 0.5842)
					(thickness 0.1524)
				)
			)
		)
		(property "Device Type" "RESISTOR-G155-133R0-01,33OHM,1%"
			(at 0.008382 1.210564 180)
			(unlocked yes)
			(layer "F.Fab")
			(hide yes)
			(effects
				(font
					(size 0.7874 0.5842)
					(thickness 0.1524)
				)
			)
		)
		(duplicate_pad_numbers_are_jumpers no)
		(fp_line
			(start 1.143 0.5588)
			(end 1.143 -0.5588)
			(stroke
				(width 0.1)
				(type default)
			)
			(layer "F.SilkS")
		)
		(fp_line
			(start 1.143 -0.5588)
			(end -1.143 -0.5588)
			(stroke
				(width 0.1)
				(type default)
			)
			(layer "F.SilkS")
		)
		(fp_line
			(start -1.143 0.5588)
			(end 1.143 0.5588)
			(stroke
				(width 0.1)
				(type default)
			)
			(layer "F.SilkS")
		)
		(fp_line
			(start -1.143 -0.5588)
			(end -1.143 0.5588)
			(stroke
				(width 0.1)
				(type default)
			)
			(layer "F.SilkS")
		)
		(fp_rect
			(start 1.143 -0.5588)
			(end -1.143 0.5588)
			(stroke
				(width 0)
				(type default)
			)
			(fill no)
			(layer "F.CrtYd")
		)
		(fp_line
			(start 0.508 0.3048)
			(end 0.508 -0.3048)
			(stroke
				(width 0.1)
				(type default)
			)
			(layer "F.Fab")
		)
		(fp_line
			(start 0.508 -0.3048)
			(end -0.508 -0.3048)
			(stroke
				(width 0.1)
				(type default)
			)
			(layer "F.Fab")
		)
		(fp_line
			(start -0.508 0.3048)
			(end 0.508 0.3048)
			(stroke
				(width 0.1)
				(type default)
			)
			(layer "F.Fab")
		)
		(fp_line
			(start -0.508 -0.3048)
			(end -0.508 0.3048)
			(stroke
				(width 0.1)
				(type default)
			)
			(layer "F.Fab")
		)
		(pad "1" smd rect
			(at -0.5334 0 180)
			(size 0.7112 0.6096)
			(layers "F.Cu" "F.Mask" "F.Paste")
			(net "EEPROM_I2C_SCL")
		)
		(pad "2" smd rect
			(at 0.5334 0 180)
			(size 0.7112 0.6096)
			(layers "F.Cu" "F.Mask" "F.Paste")
			(net "EEPROM_SCL")
		)
		(zone
			(layer "F.Cu")
			(hatch none 0.5)
			(connect_pads
				(clearance 0)
			)
			(min_thickness 0.25)
			(keepout
				(tracks allowed)
				(vias not_allowed)
				(pads allowed)
				(copperpour not_allowed)
				(footprints allowed)
			)
			(placement
				(enabled no)
				(sheetname "")
			)
			(fill
				(thermal_gap 0.5)
				(thermal_bridge_width 0.5)
				(island_removal_mode 0)
			)
			(polygon
				(pts
					(xy 33.69818 -17.6784) (xy 33.85058 -17.6784) (xy 33.85058 -18.288) (xy 33.69818 -18.288)
				)
			)
		)
	)
	(footprint ""
		(layer "F.Cu")
		(at 122.809 -89.535 -90)
		(property "Reference" "R117"
			(at 3.429 -0.29337 90)
			(unlocked yes)
			(layer "F.SilkS")
			(effects
				(font
					(size 0.7874 0.5842)
					(thickness 0.1524)
				)
			)
		)
		(property "Value" "VAL*"
			(at 0.02032 2.13233 270)
			(unlocked yes)
			(layer "F.Fab")
			(hide yes)
			(effects
				(font
					(size 0.7874 0.5842)
					(thickness 0.1524)
				)
			)
		)
		(property "Device Type" "RESISTOR-G155-133R0-01,33OHM,1%"
			(at 0.008382 1.210564 270)
			(unlocked yes)
			(layer "F.Fab")
			(hide yes)
			(effects
				(font
					(size 0.7874 0.5842)
					(thickness 0.1524)
				)
			)
		)
		(property "User Part Number" "PARTNUM*"
			(at 0.02032 4.024884 270)
			(unlocked yes)
			(layer "Cmts.User")
			(hide yes)
			(effects
				(font
					(size 0.7874 0.5842)
					(thickness 0.1524)
				)
			)
		)
		(property "Tolerance" "TOL*"
			(at 0.044704 3.05435 270)
			(unlocked yes)
			(layer "Cmts.User")
			(hide yes)
			(effects
				(font
					(size 0.7874 0.5842)
					(thickness 0.1524)
				)
			)
		)
		(duplicate_pad_numbers_are_jumpers no)
		(fp_line
			(start -1.143 0.5588)
			(end 1.143 0.5588)
			(stroke
				(width 0.1)
				(type default)
			)
			(layer "F.SilkS")
		)
		(fp_line
			(start 1.143 0.5588)
			(end 1.143 -0.5588)
			(stroke
				(width 0.1)
				(type default)
			)
			(layer "F.SilkS")
		)
		(fp_line
			(start -1.143 -0.5588)
			(end -1.143 0.5588)
			(stroke
				(width 0.1)
				(type default)
			)
			(layer "F.SilkS")
		)
		(fp_line
			(start 1.143 -0.5588)
			(end -1.143 -0.5588)
			(stroke
				(width 0.1)
				(type default)
			)
			(layer "F.SilkS")
		)
		(fp_rect
			(start 1.143 -0.5588)
			(end -1.143 0.5588)
			(stroke
				(width 0)
				(type default)
			)
			(fill no)
			(layer "F.CrtYd")
		)
		(fp_line
			(start -0.508 0.3048)
			(end 0.508 0.3048)
			(stroke
				(width 0.1)
				(type default)
			)
			(layer "F.Fab")
		)
		(fp_line
			(start 0.508 0.3048)
			(end 0.508 -0.3048)
			(stroke
				(width 0.1)
				(type default)
			)
			(layer "F.Fab")
		)
		(fp_line
			(start -0.508 -0.3048)
			(end -0.508 0.3048)
			(stroke
				(width 0.1)
				(type default)
			)
			(layer "F.Fab")
		)
		(fp_line
			(start 0.508 -0.3048)
			(end -0.508 -0.3048)
			(stroke
				(width 0.1)
				(type default)
			)
			(layer "F.Fab")
		)
		(pad "1" smd rect
			(at -0.5334 0 270)
			(size 0.7112 0.6096)
			(layers "F.Cu" "F.Mask" "F.Paste")
			(net "GPSTP1_OUT")
		)
		(pad "2" smd rect
			(at 0.5334 0 270)
			(size 0.7112 0.6096)
			(layers "F.Cu" "F.Mask" "F.Paste")
			(net "FPGA_IN_GPSTP1_OUT")
		)
		(zone
			(layer "F.Cu")
			(hatch none 0.5)
			(connect_pads
				(clearance 0)
			)
			(min_thickness 0.25)
			(keepout
				(tracks allowed)
				(vias not_allowed)
				(pads allowed)
				(copperpour not_allowed)
				(footprints allowed)
			)
			(placement
				(enabled no)
				(sheetname "")
			)
			(fill
				(thermal_gap 0.5)
				(thermal_bridge_width 0.5)
				(island_removal_mode 0)
			)
			(polygon
				(pts
					(xy 123.1138 -89.4588) (xy 123.1138 -89.6112) (xy 122.5042 -89.6112) (xy 122.5042 -89.4588)
				)
			)
		)
	)
	(footprint ""
		(layer "F.Cu")
		(at 14.5034 -98.3488 90)
		(property "Reference" "L20"
			(at -1.1303 -1.25603 90)
			(unlocked yes)
			(layer "F.SilkS")
			(effects
				(font
					(size 0.7874 0.5842)
					(thickness 0.1524)
				)
				(justify left)
			)
		)
		(property "Value" "VAL*"
			(at -0.9398 3.70967 90)
			(unlocked yes)
			(layer "F.Fab")
			(hide yes)
			(effects
				(font
					(size 0.7874 0.5842)
					(thickness 0.1524)
				)
				(justify left)
			)
		)
		(property "Tolerance" "TOL*"
			(at -0.9906 5.00507 90)
			(unlocked yes)
			(layer "Cmts.User")
			(hide yes)
			(effects
				(font
					(size 0.7874 0.5842)
					(thickness 0.1524)
				)
				(justify left)
			)
		)
		(property "User Part Number" "PARTNUM*"
			(at -2.54 2.46507 90)
			(unlocked yes)
			(layer "Cmts.User")
			(hide yes)
			(effects
				(font
					(size 0.7874 0.5842)
					(thickness 0.1524)
				)
				(justify left)
			)
		)
		(property "Device Type" "FERRITEBEAD-G191-10101-01,26OHA"
			(at -0.9906 1.22047 90)
			(unlocked yes)
			(layer "F.Fab")
			(hide yes)
			(effects
				(font
					(size 0.7874 0.5842)
					(thickness 0.1524)
				)
				(justify left)
			)
		)
		(duplicate_pad_numbers_are_jumpers no)
		(fp_line
			(start 1.3208 -0.7112)
			(end 1.3208 0.7112)
			(stroke
				(width 0.1)
				(type default)
			)
			(layer "F.SilkS")
		)
		(fp_line
			(start -1.3208 -0.7112)
			(end 1.3208 -0.7112)
			(stroke
				(width 0.1)
				(type default)
			)
			(layer "F.SilkS")
		)
		(fp_line
			(start 1.3208 0.7112)
			(end -1.3208 0.7112)
			(stroke
				(width 0.1)
				(type default)
			)
			(layer "F.SilkS")
		)
		(fp_line
			(start -1.3208 0.7112)
			(end -1.3208 -0.7112)
			(stroke
				(width 0.1)
				(type default)
			)
			(layer "F.SilkS")
		)
		(fp_rect
			(start -1.3208 0.7112)
			(end 1.3208 -0.7112)
			(stroke
				(width 0)
				(type default)
			)
			(fill no)
			(layer "F.CrtYd")
		)
		(fp_line
			(start 0.8128 -0.4572)
			(end 0.8128 0.4572)
			(stroke
				(width 0.1)
				(type default)
			)
			(layer "F.Fab")
		)
		(fp_line
			(start -0.8128 -0.4572)
			(end 0.8128 -0.4572)
			(stroke
				(width 0.1)
				(type default)
			)
			(layer "F.Fab")
		)
		(fp_line
			(start 0.8128 0.4572)
			(end -0.8128 0.4572)
			(stroke
				(width 0.1)
				(type default)
			)
			(layer "F.Fab")
		)
		(fp_line
			(start -0.8128 0.4572)
			(end -0.8128 -0.4572)
			(stroke
				(width 0.1)
				(type default)
			)
			(layer "F.Fab")
		)
		(pad "1" smd rect
			(at -0.6858 0 90)
			(size 0.762 0.8636)
			(layers "F.Cu" "F.Mask" "F.Paste")
			(net "XP12R0V_PCIE")
		)
		(pad "2" smd rect
			(at 0.6858 0 90)
			(size 0.762 0.8636)
			(layers "F.Cu" "F.Mask" "F.Paste")
			(net "XP12R0V_IN")
		)
		(zone
			(layer "F.Cu")
			(hatch none 0.5)
			(connect_pads
				(clearance 0)
			)
			(min_thickness 0.25)
			(keepout
				(tracks not_allowed)
				(vias allowed)
				(pads allowed)
				(copperpour not_allowed)
				(footprints allowed)
			)
			(placement
				(enabled no)
				(sheetname "")
			)
			(fill
				(thermal_gap 0.5)
				(thermal_bridge_width 0.5)
				(island_removal_mode 0)
			)
			(polygon
				(pts
					(xy 14.9606 -98.1964) (xy 14.9606 -98.5012) (xy 14.0462 -98.5012) (xy 14.0462 -98.1964)
				)
			)
		)
		(zone
			(layer "F.Cu")
			(hatch none 0.5)
			(connect_pads
				(clearance 0)
			)
			(min_thickness 0.25)
			(keepout
				(tracks allowed)
				(vias not_allowed)
				(pads allowed)
				(copperpour not_allowed)
				(footprints allowed)
			)
			(placement
				(enabled no)
				(sheetname "")
			)
			(fill
				(thermal_gap 0.5)
				(thermal_bridge_width 0.5)
				(island_removal_mode 0)
			)
			(polygon
				(pts
					(xy 14.9606 -98.1964) (xy 14.9606 -98.5012) (xy 14.0462 -98.5012) (xy 14.0462 -98.1964)
				)
			)
		)
	)
	(footprint ""
		(layer "F.Cu")
		(at 108.0516 -58.3184)
		(property "Reference" "TP188"
			(at 2.85115 2.1082 90)
			(unlocked yes)
			(layer "F.SilkS")
			(effects
				(font
					(size 0.635 0.4064)
					(thickness 0.1524)
				)
				(justify left)
			)
		)
		(property "Value" ""
			(at 0 0 0)
			(layer "F.Fab")
			(effects
				(font
					(size 1.27 1.27)
				)
			)
		)
		(property "Device Type" "TP_PIONT-TP010CT020B030_PTH-TPA"
			(at -1.341882 0.996696 0)
			(unlocked yes)
			(layer "F.Fab")
			(hide yes)
			(effects
				(font
					(size 0.7874 0.5842)
					(thickness 0.1524)
				)
				(justify left)
			)
		)
		(duplicate_pad_numbers_are_jumpers no)
		(fp_poly
			(pts
				(arc
					(start 0.889 0)
					(mid -0.889 0)
					(end 0.889 0)
				)
			)
			(stroke
				(width 0)
				(type default)
			)
			(fill no)
			(layer "B.CrtYd")
		)
		(fp_poly
			(pts
				(arc
					(start 0.889 0)
					(mid -0.889 0)
					(end 0.889 0)
				)
			)
			(stroke
				(width 0)
				(type default)
			)
			(fill no)
			(layer "F.CrtYd")
		)
		(pad "1" thru_hole circle
			(at 0 0)
			(size 0.508 0.508)
			(drill 0.254)
			(layers "*.Cu" "*.Mask")
			(remove_unused_layers no)
			(net "IO_L24N_16")
			(clearance 0.1016)
			(padstack
				(mode front_inner_back)
				(layer "Inner"
					(shape circle)
					(size 0.508 0.508)
					(clearance 0.1016)
				)
				(layer "B.Cu"
					(shape circle)
					(size 0.762 0.762)
					(clearance -0.0254)
				)
			)
		)
	)
	(footprint ""
		(layer "F.Cu")
		(at 46.101 -82.804)
		(property "Reference" "C284"
			(at 0.127 -2.24663 0)
			(unlocked yes)
			(layer "F.SilkS")
			(effects
				(font
					(size 0.7874 0.5842)
					(thickness 0.1524)
				)
			)
		)
		(property "Value" "VAL*"
			(at 0.0762 3.134106 0)
			(unlocked yes)
			(layer "F.Fab")
			(hide yes)
			(effects
				(font
					(size 0.7874 0.5842)
					(thickness 0.1524)
				)
			)
		)
		(property "Tolerance" "TOL*"
			(at 0.0762 4.048506 0)
			(unlocked yes)
			(layer "Cmts.User")
			(hide yes)
			(effects
				(font
					(size 0.7874 0.5842)
					(thickness 0.1524)
				)
			)
		)
		(property "User Part Number" "PARTNUM*"
			(at 0.1016 5.013706 0)
			(unlocked yes)
			(layer "Cmts.User")
			(hide yes)
			(effects
				(font
					(size 0.7874 0.5842)
					(thickness 0.1524)
				)
			)
		)
		(property "Device Type" "CAPACITOR-G107-0F226-CM,22UF,2A"
			(at 0.0508 2.194306 0)
			(unlocked yes)
			(layer "F.Fab")
			(hide yes)
			(effects
				(font
					(size 0.7874 0.5842)
					(thickness 0.1524)
				)
			)
		)
		(duplicate_pad_numbers_are_jumpers no)
		(fp_line
			(start -1.5748 -0.9398)
			(end -1.5748 0.9398)
			(stroke
				(width 0.1)
				(type default)
			)
			(layer "F.SilkS")
		)
		(fp_line
			(start -1.5748 0.9398)
			(end 1.5748 0.9398)
			(stroke
				(width 0.1)
				(type default)
			)
			(layer "F.SilkS")
		)
		(fp_line
			(start 1.5748 -0.9398)
			(end -1.5748 -0.9398)
			(stroke
				(width 0.1)
				(type default)
			)
			(layer "F.SilkS")
		)
		(fp_line
			(start 1.5748 0.9398)
			(end 1.5748 -0.9398)
			(stroke
				(width 0.1)
				(type default)
			)
			(layer "F.SilkS")
		)
		(fp_poly
			(pts
				(xy -1.5748 0.9398) (xy 1.5748 0.9398) (xy 1.5748 -0.9398) (xy -1.5748 -0.9398)
			)
			(stroke
				(width 0)
				(type default)
			)
			(fill no)
			(layer "F.CrtYd")
		)
		(fp_line
			(start -1.016 -0.635)
			(end -1.016 0.635)
			(stroke
				(width 0.1)
				(type default)
			)
			(layer "F.Fab")
		)
		(fp_line
			(start -1.016 0.635)
			(end 1.016 0.635)
			(stroke
				(width 0.1)
				(type default)
			)
			(layer "F.Fab")
		)
		(fp_line
			(start 1.016 -0.635)
			(end -1.016 -0.635)
			(stroke
				(width 0.1)
				(type default)
			)
			(layer "F.Fab")
		)
		(fp_line
			(start 1.016 0.635)
			(end 1.016 -0.635)
			(stroke
				(width 0.1)
				(type default)
			)
			(layer "F.Fab")
		)
		(pad "1" smd rect
			(at -0.8382 0)
			(size 0.9652 1.3716)
			(layers "F.Cu" "F.Mask" "F.Paste")
			(net "UNNAMED_525_CAPACITOR_I7_1")
		)
		(pad "2" smd rect
			(at 0.8382 0)
			(size 0.9652 1.3716)
			(layers "F.Cu" "F.Mask" "F.Paste")
			(net "SG")
		)
		(zone
			(layer "F.Cu")
			(hatch none 0.5)
			(connect_pads
				(clearance 0)
			)
			(min_thickness 0.25)
			(keepout
				(tracks not_allowed)
				(vias allowed)
				(pads allowed)
				(copperpour not_allowed)
				(footprints allowed)
			)
			(placement
				(enabled no)
				(sheetname "")
			)
			(fill
				(thermal_gap 0.5)
				(thermal_bridge_width 0.5)
				(island_removal_mode 0)
			)
			(polygon
				(pts
					(xy 45.8724 -82.169) (xy 46.3296 -82.169) (xy 46.3296 -83.439) (xy 45.8724 -83.439)
				)
			)
		)
		(zone
			(layer "F.Cu")
			(hatch none 0.5)
			(connect_pads
				(clearance 0)
			)
			(min_thickness 0.25)
			(keepout
				(tracks allowed)
				(vias not_allowed)
				(pads allowed)
				(copperpour not_allowed)
				(footprints allowed)
			)
			(placement
				(enabled no)
				(sheetname "")
			)
			(fill
				(thermal_gap 0.5)
				(thermal_bridge_width 0.5)
				(island_removal_mode 0)
			)
			(polygon
				(pts
					(xy 45.8724 -82.169) (xy 46.3296 -82.169) (xy 46.3296 -83.439) (xy 45.8724 -83.439)
				)
			)
		)
	)
	(footprint ""
		(layer "F.Cu")
		(at 5.842 -81.534 90)
		(property "Reference" "R425"
			(at -2.667 -0.34163 90)
			(unlocked yes)
			(layer "F.SilkS")
			(effects
				(font
					(size 0.7874 0.5842)
					(thickness 0.1524)
				)
			)
		)
		(property "Value" "VAL*"
			(at 0.02032 2.13233 90)
			(unlocked yes)
			(layer "F.Fab")
			(hide yes)
			(effects
				(font
					(size 0.7874 0.5842)
					(thickness 0.1524)
				)
			)
		)
		(property "Device Type" "RESISTOR-G155-11000-01,100OHM,A"
			(at 0.008382 1.210564 90)
			(unlocked yes)
			(layer "F.Fab")
			(hide yes)
			(effects
				(font
					(size 0.7874 0.5842)
					(thickness 0.1524)
				)
			)
		)
		(property "User Part Number" "PARTNUM*"
			(at 0.02032 4.024884 90)
			(unlocked yes)
			(layer "Cmts.User")
			(hide yes)
			(effects
				(font
					(size 0.7874 0.5842)
					(thickness 0.1524)
				)
			)
		)
		(property "Tolerance" "TOL*"
			(at 0.044704 3.05435 90)
			(unlocked yes)
			(layer "Cmts.User")
			(hide yes)
			(effects
				(font
					(size 0.7874 0.5842)
					(thickness 0.1524)
				)
			)
		)
		(duplicate_pad_numbers_are_jumpers no)
		(fp_line
			(start 1.143 -0.5588)
			(end -1.143 -0.5588)
			(stroke
				(width 0.1)
				(type default)
			)
			(layer "F.SilkS")
		)
		(fp_line
			(start -1.143 -0.5588)
			(end -1.143 0.5588)
			(stroke
				(width 0.1)
				(type default)
			)
			(layer "F.SilkS")
		)
		(fp_line
			(start 1.143 0.5588)
			(end 1.143 -0.5588)
			(stroke
				(width 0.1)
				(type default)
			)
			(layer "F.SilkS")
		)
		(fp_line
			(start -1.143 0.5588)
			(end 1.143 0.5588)
			(stroke
				(width 0.1)
				(type default)
			)
			(layer "F.SilkS")
		)
		(fp_poly
			(pts
				(xy -1.143 0.5588) (xy 1.143 0.5588) (xy 1.143 -0.5588) (xy -1.143 -0.5588)
			)
			(stroke
				(width 0)
				(type default)
			)
			(fill no)
			(layer "F.CrtYd")
		)
		(fp_line
			(start 0.508 -0.3048)
			(end -0.508 -0.3048)
			(stroke
				(width 0.1)
				(type default)
			)
			(layer "F.Fab")
		)
		(fp_line
			(start -0.508 -0.3048)
			(end -0.508 0.3048)
			(stroke
				(width 0.1)
				(type default)
			)
			(layer "F.Fab")
		)
		(fp_line
			(start 0.508 0.3048)
			(end 0.508 -0.3048)
			(stroke
				(width 0.1)
				(type default)
			)
			(layer "F.Fab")
		)
		(fp_line
			(start -0.508 0.3048)
			(end 0.508 0.3048)
			(stroke
				(width 0.1)
				(type default)
			)
			(layer "F.Fab")
		)
		(pad "1" smd rect
			(at -0.5334 0 90)
			(size 0.7112 0.6096)
			(layers "F.Cu" "F.Mask" "F.Paste")
			(net "FPGA_OUT_GPS_LED_BLUE_N")
		)
		(pad "2" smd rect
			(at 0.5334 0 90)
			(size 0.7112 0.6096)
			(layers "F.Cu" "F.Mask" "F.Paste")
			(net "UNNAMED_14_LED4PV14_I269_1")
		)
		(zone
			(layer "F.Cu")
			(hatch none 0.5)
			(connect_pads
				(clearance 0)
			)
			(min_thickness 0.25)
			(keepout
				(tracks not_allowed)
				(vias allowed)
				(pads allowed)
				(copperpour not_allowed)
				(footprints allowed)
			)
			(placement
				(enabled no)
				(sheetname "")
			)
			(fill
				(thermal_gap 0.5)
				(thermal_bridge_width 0.5)
				(island_removal_mode 0)
			)
			(polygon
				(pts
					(xy 6.1468 -81.4578) (xy 6.1468 -81.6102) (xy 5.5372 -81.6102) (xy 5.5372 -81.4578)
				)
			)
		)
		(zone
			(layer "F.Cu")
			(hatch none 0.5)
			(connect_pads
				(clearance 0)
			)
			(min_thickness 0.25)
			(keepout
				(tracks allowed)
				(vias not_allowed)
				(pads allowed)
				(copperpour not_allowed)
				(footprints allowed)
			)
			(placement
				(enabled no)
				(sheetname "")
			)
			(fill
				(thermal_gap 0.5)
				(thermal_bridge_width 0.5)
				(island_removal_mode 0)
			)
			(polygon
				(pts
					(xy 6.1468 -81.4578) (xy 6.1468 -81.6102) (xy 5.5372 -81.6102) (xy 5.5372 -81.4578)
				)
			)
		)
	)
)
